# SCM (Grand Teton) — schematic parts with pin connectivity, parts 1006–1164 of 1428; source: Cadence DE-HDL packaged netlist (pstxprt.dat, pstxnet.dat, pstchip.dat)

R509  Q_RES  33.2 1% CHIP  pkg 0402LF  page 48 : 1 = MB_JTAG_PLD_R_JTAGEN ; 2 = JTAG_SCM_PLD_JTAGEN
R510  Q_RES  33.2 1% CHIP  pkg 0402LF  page 32 : 1 = JTAG_SCM_TCK ; 2 = JTAG_SCM_PLD_TCK
R511  Q_RES  33.2 1% CHIP  pkg 0402LF  page 32 : 1 = JTAG_SCM_TMS ; 2 = JTAG_SCM_PLD_TMS
R512  Q_RES  33.2 1% CHIP  pkg 0402LF  page 32 : 1 = JTAG_SCM_TDI ; 2 = JTAG_SCM_PLD_TDI
R513  Q_RES  33.2 1% CHIP  pkg 0402LF  page 32 : 1 = JTAG_SCM_TDO ; 2 = JTAG_SCM_PLD_TDO
R514  Q_RES  33.2 1% CHIP  pkg 0402LF  page 32 : 1 = JTAG_SCM_PLD_TCK ; 2 = JTAG_SCM_CONN_TCK
R515  Q_RES  33.2 1% CHIP  pkg 0402LF  page 32 : 1 = JTAG_SCM_PLD_TMS ; 2 = JTAG_SCM_CONN_TMS
R516  Q_RES  33.2 1% CHIP  pkg 0402LF  page 32 : 1 = JTAG_SCM_PLD_TDI ; 2 = JTAG_SCM_CONN_TDI
R517  Q_RES  33.2 1% CHIP  pkg 0402LF  page 32 : 1 = JTAG_SCM_PLD_TDO ; 2 = JTAG_SCM_CONN_TDO
R518  Q_RES  33.2 1% CHIP  pkg 0402LF  page 32 : 1 = JTAG_SCM_PLD_R1_JTAGEN ; 2 = JTAG_SCM_PLD_JTAGEN
R519  Q_RES  0 5% CHIP  pkg 0402LF  page 34 : 1 = BMC_CPLD_GPIO_2 ; 2 = BMC_CPLD_GPIO_2_R2
R521  Q_RES  10K 1% CHIP  pkg 0402LF  page 27 : 1 = P3V3_AUX ; 2 = SMB_BMC_MM10_SDA
R523  Q_RES  10K 1% CHIP  pkg 0402LF  page 32 : 1 = P3V3_RGM ; 2 = JTAG_SCM_TDO
R525  Q_RES  0 5% CHIP  pkg 0402LF  page 41 : 1 = P3V3_AUX ; 2 = VCCIO1
R526  Q_RES  33.2 1% EMPTY  pkg 0402LF  page 35 : 1 = BMC_CPLD_GPIO_7_R2 ; 2 = BMC_CPLD_GPIO_7
R527  Q_RES  0 5% CHIP  pkg 0402LF  page 15 : 1 = USB_HOST_BMC_B_R_DP ; 2 = USB_HOST_BMC_B_DP
R528  Q_RES  0 5% CHIP  pkg 0402LF  page 15 : 1 = USB_HOST_BMC_B_R_DN ; 2 = USB_HOST_BMC_B_DN
R529  Q_RES  100 1% CHIP  pkg 0402LF  page 52 : 1 = PWRGD_P1V8_AUX ; 2 = PWRGD_P1V8_AUX_R2
R530  Q_RES  100 1% CHIP  pkg 0402LF  page 54 : 1 = PWRGD_P3V3_RGM ; 2 = PWRGD_P3V3_RGM_R2
R531  Q_RES  33.2 1% EMPTY  pkg 0402LF  page 35 : 1 = BMC_CPLD_GPIO_8_R2 ; 2 = BMC_CPLD_GPIO_8
R532  Q_RES  33.2 1% EMPTY  pkg 0402LF  page 21 : 1 = EMMC_DT3_R ; 2 = BMC_EMMC_DT3
R536  Q_RES  33.2 1% CHIP  pkg 0402LF  page 35 : 1 = BMC_CPLD_GPIO_12_R2 ; 2 = BMC_CPLD_GPIO_12
R537  Q_RES  33.2 1% CHIP  pkg 0402LF  page 35 : 1 = BMC_CPLD_GPIO_13_R2 ; 2 = BMC_CPLD_GPIO_13
R538  Q_RES  100K 1% CHIP  pkg 0402LF  page 31 : 1 = P3V3_AUX ; 2 = UART_6_BMC_RXD_R
R543  Q_RES  4.7K 1% EMPTY  pkg 0402LF  page 21 : 1 = P3V3_AUX ; 2 = SPI_BMC_HOLD1_N
R544  Q_RES  0 5% CHIP  pkg 0402LF  page 31 : 1 = UART_SYS_DBG_TX ; 2 = UART_SYS_DBG_TX_R
R545  Q_RES  0 5% CHIP  pkg 0402LF  page 25 : 1 = GND ; 2 = FLASH_LATCH_CP
R546  Q_RES  0 5% CHIP  pkg 0402LF  page 31 : 1 = SPA_SOUT_SW_DBG ; 2 = SPA_SOUT_SW_DBG_R
R547  Q_RES  33.2 1% CHIP  pkg 0402LF  page 21 : 1 = SPI_BMC_CS1_FLASH_R_N ; 2 = SPI_BMC_BOOT_CS1_R_N
R548  Q_RES  33.2 1% CHIP  pkg 0402LF  page 25 : 1 = BMC_RSTIND_N ; 2 = RD_N
R549  Q_RES  33.2 1% CHIP  pkg 0402LF  page 21 : 1 = SPI_BMC_CLK_FLASH_R ; 2 = SPI_BMC_BOOT_CLK
R550  Q_RES  33.2 1% CHIP  pkg 0402LF  page 21 : 1 = SPI_BMC_IO0_FLASH_R ; 2 = SPI_BMC_BOOT_MOSI
R551  Q_RES  33.2 1% CHIP  pkg 0402LF  page 25 : 1 = FLASH_WP_STATUS ; 2 = FLASH_R_WP_STATUS
R552  Q_RES  33.2 1% CHIP  pkg 0402LF  page 21 : 1 = SPI_BMC_IO1_FLASH_R ; 2 = SPI_BMC_BOOT_MISO
R553  Q_RES  33.2 1% CHIP  pkg 0402LF  page 21 : 1 = SPI_BMC_CS0_FLASH_R_N ; 2 = SPI_BMC_BOOT_CS0_R_N
R554  Q_RES  4.7K 1% EMPTY  pkg 0402LF  page 25 : 1 = P3V3_AUX ; 2 = FLASH_R_WP_STATUS
R555  Q_RES  33.2 1% CHIP  pkg 0402LF  page 25 : 1 = FLASH_LATCH_Q_N_R ; 2 = FLASH_LATCH_Q_N_R1
R556  Q_RES  33.2 1% CHIP  pkg 0402LF  page 25 : 1 = SPI_BMC_BT_WP1_N_R ; 2 = FLASH_LATCH_Q_N_R2
R557  Q_RES  4.7K 1% CHIP  pkg 0402LF  page 21 : 1 = P3V3_AUX ; 2 = SPI_BMC_CS0_FLASH_R_N
R558  Q_RES  4.7K 1% CHIP  pkg 0402LF  page 21 : 1 = P3V3_AUX ; 2 = SPI_BMC_CS1_FLASH_R_N
R559  Q_RES  33.2 1% CHIP  pkg 0402LF  page 25 : 1 = SPI_BMC_BT_WP0_N_R ; 2 = FLASH_LATCH_Q_N_R2
R560  Q_RES  0 5% CHIP  pkg 0402LF  page 25 : 1 = FLASH_LATCH_Q_N_R1 ; 2 = FLASH_LATCH_Q_N_R2
R561  Q_RES  33.2 1% EMPTY  pkg 0402LF  page 21 : 1 = RST_SPI_BMC_FLASH_R2_N ; 2 = RST_SPI_FLASH_BUF_N
R562  Q_RES  33.2 1% CHIP  pkg 0402LF  page 21 : 1 = RST_SPI_BMC_FLASH_R1_N ; 2 = RST_SPI_FLASH_BUF_N
R563  Q_RES  4.7K 1% CHIP  pkg 0402LF  page 25 : 1 = P3V3_AUX ; 2 = RST_SPI_FLASH_BUF_N
R564  Q_RES  0 5% EMPTY  pkg 0402LF  page 10 : 1 = HDD_LED_N ; 2 = HDD_LED_R_N
R565  Q_RES  100 1% CHIP  pkg 0402LF  page 15 : 1 = ID_RST_BTN_BMC_R_N ; 2 = ID_RST_BTN_BMC_N
R566  Q_RES  0 5% CHIP  pkg 0402LF  page 15 : 1 = RST_BMC_RSTBTN_OUT_R_N ; 2 = RST_BMC_RSTBTN_OUT_N
R567  Q_RES  33.2 1% CHIP  pkg 0402LF  page 12 : 1 = SMB_BMC_MM7_R_SCL ; 2 = SMB_BMC_MM7_SCL
R568  Q_RES  220 1% CHIP  pkg 0402LF  page 49 : 1 = PWR_LED_P5V_AUX ; 2 = P5V_AUX
R569  Q_RES  220 1% CHIP  pkg 0402LF  page 49 : 1 = HDD_LED_P5V_AUX ; 2 = P5V_AUX
R570  Q_RES  33.2 1% CHIP  pkg 0402LF  page 12 : 1 = SMB_BMC_MM7_R_SDA ; 2 = SMB_BMC_MM7_SDA
R571  Q_RES  0 5% CHIP  pkg 0402LF  page 34 : 1 = IRQ_BMC_PCH_NMI_N ; 2 = IRQ_BMC_PCH_NMI_R_N
R574  Q_RES  0 5% CHIP  pkg 0402LF  page 35 : 1 = SMB_BMC_ALERT16_N ; 2 = SMB_BMC_ALERT16_R2_N
R575  Q_RES  0 5% CHIP  pkg 0402LF  page 36 : 1 = FM_P12V_HSC_ENABLE ; 2 = FM_P12V_HSC_ENABLE_R2
R577  Q_RES  0 5% CHIP  pkg 0402LF  page 36 : 1 = FM_SOL_UART_CH_SEL ; 2 = FM_SOL_UART_CH_SEL_R2
R578  Q_RES  0 5% CHIP  pkg 0402LF  page 36 : 1 = PWRGD_DSW_PWROK ; 2 = PWRGD_DSW_PWROK_R2
R579  Q_RES  0 5% CHIP  pkg 0402LF  page 36 : 1 = FM_DEBUG_PORT_PRSNT_N ; 2 = FM_DEBUG_PORT_R2_PRSNT_N
R580  Q_RES  33.2 1% CHIP  pkg 0402LF  page 12 : 1 = SMB_BMC_MM9_R_SCL ; 2 = SMB_BMC_MM9_SCL
R582  Q_RES  33.2 1% CHIP  pkg 0402LF  page 12 : 1 = SMB_BMC_MM9_R_SDA ; 2 = SMB_BMC_MM9_SDA
R583  Q_RES  33.2 1% CHIP  pkg 0402LF  page 12 : 1 = SMB_BMC_MM10_R_SCL ; 2 = SMB_BMC_MM10_SCL
R584  Q_RES  33.2 1% CHIP  pkg 0402LF  page 12 : 1 = SMB_BMC_MM10_R_SDA ; 2 = SMB_BMC_MM10_SDA
R585  Q_RES  33.2 1% CHIP  pkg 0402LF  page 15 : 1 = BMC_RSTIND_N ; 2 = RST_SPI_FLASH_N
R586  Q_RES  4.7K 1% CHIP  pkg 0402LF  page 42 : 1 = P3V3_AUX ; 2 = BMC_CPLD_GPIO_2
R589  Q_RES  33.2 1% CHIP  pkg 0402LF  page 12 : 1 = SMB_BMC_MM3_R_SCL ; 2 = SMB_BMC_MM3_SCL
R590  Q_RES  33.2 1% CHIP  pkg 0402LF  page 12 : 1 = SMB_BMC_MM3_R_SDA ; 2 = SMB_BMC_MM3_SDA
R592  Q_RES  4.7K 1% CHIP  pkg 0402LF  page 25 : 1 = P3V3_AUX ; 2 = PU_J1_P1
R593  Q_RES  4.7K 1% EMPTY  pkg 0402LF  page 42 : 1 = P3V3_AUX ; 2 = BMC_CPLD_GPIO_7
R594  Q_RES  33.2 1% CHIP  pkg 0402LF  page 44 : 1 = SPI_TPM_CS_N ; 2 = SPI_TPM_CS_R_N
R595  Q_RES  4.7K 1% EMPTY  pkg 0402LF  page 42 : 1 = P3V3_AUX ; 2 = BMC_CPLD_GPIO_8
R597  Q_RES  750 1% CHIP  pkg 0402LF  page 47 : 1 = LED_POSTCODE_7 ; 2 = LED_POSTCODE_7_R
R598  Q_RES  750 1% CHIP  pkg 0402LF  page 47 : 1 = LED_POSTCODE_6 ; 2 = LED_POSTCODE_6_R
R599  Q_RES  750 1% CHIP  pkg 0402LF  page 47 : 1 = LED_POSTCODE_5 ; 2 = LED_POSTCODE_5_R
R600  Q_RES  750 1% CHIP  pkg 0402LF  page 47 : 1 = LED_POSTCODE_4 ; 2 = LED_POSTCODE_4_R
R601  Q_RES  750 1% CHIP  pkg 0402LF  page 47 : 1 = LED_POSTCODE_3 ; 2 = LED_POSTCODE_3_R
R602  Q_RES  750 1% CHIP  pkg 0402LF  page 47 : 1 = LED_POSTCODE_2 ; 2 = LED_POSTCODE_2_R
R603  Q_RES  750 1% CHIP  pkg 0402LF  page 47 : 1 = LED_POSTCODE_1 ; 2 = LED_POSTCODE_1_R
R604  Q_RES  750 1% CHIP  pkg 0402LF  page 47 : 1 = LED_POSTCODE_0 ; 2 = LED_POSTCODE_0_R
R607  Q_RES  4.7K 1% CHIP  pkg 0402LF  page 42 : 1 = P3V3_AUX ; 2 = BMC_CPLD_GPIO_12
R608  Q_RES  4.7K 1% CHIP  pkg 0402LF  page 42 : 1 = P3V3_AUX ; 2 = BMC_CPLD_GPIO_13
R610  Q_RES  2.2K 5% CHIP  pkg 0402LF  page 27 : 1 = P3V3_AUX ; 2 = SMB_BMC_MM15_SCL
R614  Q_RES  100K 1% CHIP  pkg 0402LF  page 22 : 1 = RST_SRST_PLD_BMC_R1_N ; 2 = GND
R615  Q_RES  4.7K 1% EMPTY  pkg 0402LF  page 48 : 1 = P3V3_AUX ; 2 = FM_BMC_DISABLE
R616  Q_RES  0 5% CHIP  pkg 0402LF  page 48 : 1 = FM_JTAG_TCK_MUX_BMC_SEL_R ; 2 = FM_JTAG_TCK_MUX_BMC_SEL
R618  Q_RES  0 5% CHIP  pkg 0402LF  page 31 : 1 = UART_SYS_DBG_RX ; 2 = UART_SYS_DBG_RX_R
R619  Q_RES  8.2K 5% EMPTY  pkg 0402LF  page 49 : 1 = HDD_LED_N ; 2 = GND
R620  Q_RES  100K 1% CHIP  pkg 0402LF  page 48 : 1 = FM_JTAG_TCK_MUX_BMC_SEL ; 2 = GND
R621  Q_RES  4.7K 1% CHIP  pkg 0402LF  page 42 : 1 = P3V3_AUX ; 2 = FM_P12V_HSC_ENABLE
R623  Q_RES  4.7K 1% EMPTY  pkg 0402LF  page 15 : 1 = P3V3_RGM ; 2 = RST_EXTRST_N
R624  Q_RES  4.7K 1% CHIP  pkg 0402LF  page 48 : 1 = P3V3_AUX ; 2 = FM_BMC_DEBUG_SW_N
R625  Q_RES  4.7K 1% CHIP  pkg 0402LF  page 34 : 1 = P3V3_AUX ; 2 = RST_RSMRST_N
R626  Q_RES  0 5% CHIP  pkg 0402LF  page 28 : 1 = FM_SOL_UART_CH_SEL ; 2 = FM_SOL_UART_CH_SEL_R3
R627  Q_RES  4.7K 1% CHIP  pkg 0402LF  page 42 : 1 = P3V3_AUX ; 2 = PWRGD_DSW_PWROK
R628  Q_RES  100 1% CHIP  pkg 0402LF  page 31 : 1 = SPA_SIN_SW_DBG ; 2 = SPA_SIN_SW_DBG_R
R629  Q_RES  0 5% CHIP  pkg 0402LF  page 31 : 1 = BMC_CPLD_GPIO_2 ; 2 = FM_DBG_SW_N
R630  Q_RES  4.7K 1% CHIP  pkg 0402LF  page 31 : 1 = P3V3_AUX ; 2 = PU_J13_P1
R631  Q_RES  16.9K 1% CHIP  pkg 0402LF  page 51 : 1 = P3V3_LDO ; 2 = U56_ADJ_1
R632  Q_RES  0 5% CHIP  pkg 0402LF  page 28 : 1 = SMB_DEBUG_AUX_LVC3_USB_SCL ; 2 = SMB_DEBUG_AUX_LVC3_USB_R3_SCL
R633  Q_RES  1K 1% EMPTY  pkg 0402LF  page 22 : 1 = P3V3_AUX ; 2 = RST_BMC_HW_OUT
R634  Q_RES  0 5% CHIP  pkg 0402LF  page 34 : 1 = FM_JTAG_BMC_MUX_SEL ; 2 = FM_JTAG_BMC_MUX_SEL_R2
R635  Q_RES  33.2 1% CHIP  pkg 0402LF  page 36 : 1 = RST_WDTRST_PLD_N ; 2 = RST_WDTRST_PLD_R2_N
R636  Q_RES  0 5% CHIP  pkg 0402LF  page 22 : 1 = RST_EXTRST_N ; 2 = RST_BMC_EXTRST_R2_N
R637  Q_RES  0 5% CHIP  pkg 0402LF  page 13 : 1 = RST_WDTRST_PLD_R1_N ; 2 = RST_WDTRST_PLD_N
R638  Q_RES  33.2 1% CHIP  pkg 0402LF  page 35 : 1 = RST_BMC_HW_R ; 2 = RST_BMC_HW
R639  Q_RES  33.2 1% CHIP  pkg 0402LF  page 32 : 1 = JTAG_1_BMC_TDI_R ; 2 = JTAG_MB_TDI
R640  Q_RES  4.7K 1% EMPTY  pkg 0402LF  page 42 : 1 = P3V3_AUX ; 2 = FM_JTAG_BMC_MUX_SEL
R641  Q_RES  4.7K 1% EMPTY  pkg 0402LF  page 42 : 1 = P3V3_AUX ; 2 = RST_BMC_SELF_HW_R2
R642  Q_RES  100K 1% CHIP  pkg 0402LF  page 42 : 1 = GND ; 2 = FM_JTAG_BMC_MUX_SEL
R643  Q_RES  33.2 1% CHIP  pkg 0402LF  page 13 : 1 = PWRGD_DSW_PWROK ; 2 = PWRGD_DSW_PWROK_R1
R644  Q_RES  33.2 1% CHIP  pkg 0402LF  page 15 : 1 = FM_JTAG_BMC_MUX_SEL ; 2 = FM_JTAG_BMC_MUX_SEL_R1
R645  Q_RES  0 5% EMPTY  pkg 0603LF  page 17 : 1 = P1V8_AUX ; 2 = PGPPA_BMC_AUX_L
R646  Q_RES  0 5% EMPTY  pkg 0603LF  page 17 : 1 = PGPPA_BMC_AUX_L ; 2 = P3V3_AUX
R647  Q_RES  33.2 1% EMPTY  pkg 0402LF  page 21 : 1 = EMMC_DT2_R ; 2 = BMC_EMMC_DT2
R648  Q_RES  33.2 1% EMPTY  pkg 0402LF  page 21 : 1 = EMMC_DT1_R ; 2 = BMC_EMMC_DT1
R649  Q_RES  33.2 1% EMPTY  pkg 0402LF  page 21 : 1 = EMMC_DT0_R ; 2 = BMC_EMMC_DT0
R650  Q_RES  33.2 1% EMPTY  pkg 0402LF  page 21 : 1 = BMC_EMMC_DT7 ; 2 = EMMC_DT7_R
R651  Q_RES  33.2 1% EMPTY  pkg 0402LF  page 21 : 1 = BMC_EMMC_DT6 ; 2 = EMMC_DT6_R
R652  Q_RES  33.2 1% EMPTY  pkg 0402LF  page 21 : 1 = BMC_EMMC_DT5 ; 2 = EMMC_DT5_R
R653  Q_RES  33.2 1% EMPTY  pkg 0402LF  page 21 : 1 = BMC_EMMC_DT4 ; 2 = EMMC_DT4_R
R654  Q_RES  33.2 1% EMPTY  pkg 0402LF  page 21 : 1 = EMMC_CLK_R ; 2 = BMC_EMMC_CLK
R655  Q_RES  10K 1% EMPTY  pkg 0402LF  page 21 : 1 = P3V3_AUX ; 2 = EMMC_DT0_R
R656  Q_RES  10K 1% EMPTY  pkg 0402LF  page 21 : 1 = P3V3_AUX ; 2 = EMMC_DT1_R
R657  Q_RES  10K 1% EMPTY  pkg 0402LF  page 21 : 1 = P3V3_AUX ; 2 = EMMC_DT2_R
R658  Q_RES  10K 1% EMPTY  pkg 0402LF  page 21 : 1 = P3V3_AUX ; 2 = EMMC_DT3_R
R659  Q_RES  10K 1% EMPTY  pkg 0402LF  page 21 : 1 = P3V3_AUX ; 2 = EMMC_DT4_R
R660  Q_RES  10K 1% EMPTY  pkg 0402LF  page 21 : 1 = P3V3_AUX ; 2 = EMMC_DT5_R
R661  Q_RES  10K 1% EMPTY  pkg 0402LF  page 21 : 1 = P3V3_AUX ; 2 = EMMC_DT6_R
R662  Q_RES  10K 1% EMPTY  pkg 0402LF  page 21 : 1 = P3V3_AUX ; 2 = EMMC_DT7_R
R663  Q_RES  10K 1% EMPTY  pkg 0402LF  page 21 : 1 = P3V3_AUX ; 2 = EMMC_CMD_R
R664  Q_RES  1K 1% EMPTY  pkg 0402LF  page 21 : 1 = SPI_BMC_BT_WP1_N_R ; 2 = GND
R665  Q_RES  1K 1% EMPTY  pkg 0402LF  page 21 : 1 = SPI_BMC_BT_WP0_N_R ; 2 = GND
R666  Q_RES  0 5% CHIP  pkg 0402LF  page 29 : 1 = USB3_01_MUX_FB_TXN ; 2 = USB3_01_FB_TXN
R667  Q_RES  4.7K 1% CHIP  pkg 0402LF  page 28 : 1 = P3V3_AUX ; 2 = LED_POSTCODE_INT
R668  Q_RES  0 5% CHIP  pkg 0402LF  page 29 : 1 = USB3_01_MUX_FB_RXN ; 2 = USB3_01_FB_RXN
R669  Q_RES  0 5% CHIP  pkg 0402LF  page 47 : 1 = LED_POSTCODE_7 ; 2 = LED_POSTCODE_7_R1
R670  Q_RES  0 5% CHIP  pkg 0402LF  page 28 : 1 = DEBUG_PORT_PRSNT_BUF_R_EN ; 2 = DEBUG_PORT_PRSNT_BUF_EN
R671  Q_RES  0 5% CHIP  pkg 0402LF  page 29 : 1 = USB3_01_TXP_C ; 2 = USB3_FPNL_TXP
R672  Q_RES  0 5% CHIP  pkg 0402LF  page 29 : 1 = USB3_01_TXN_C ; 2 = USB3_FPNL_TXN
R673  Q_RES  0 5% CHIP  pkg 0402LF  page 29 : 1 = USB3_01_MUX_FB_TXP ; 2 = USB3_01_FB_TXP
R674  Q_RES  0 5% CHIP  pkg 0402LF  page 47 : 1 = LED_POSTCODE_6 ; 2 = LED_POSTCODE_6_R1
R675  Q_RES  0 5% CHIP  pkg 0402LF  page 29 : 1 = USB3_01_MUX_FB_RXP ; 2 = USB3_01_FB_RXP
R676  Q_RES  0 5% CHIP  pkg 0402LF  page 47 : 1 = LED_POSTCODE_5 ; 2 = LED_POSTCODE_5_R1
R677  Q_RES  10K 1% CHIP  pkg 0402LF  page 51 : 1 = U56_ADJ_1 ; 2 = GND
R678  Q_RES  33.2 1% EMPTY  pkg 0402LF  page 13 : 1 = SPI_BMC_CLK_R ; 2 = QSPI_2_PLD_CLK
R679  Q_RES  33.2 1% EMPTY  pkg 0402LF  page 13 : 1 = SPI_BMC_MOSI_IO0_R ; 2 = QSPI_2_PLD_IO0
R680  Q_RES  33.2 1% EMPTY  pkg 0402LF  page 13 : 1 = SPI_BMC_MISO_IO1_R ; 2 = QSPI_2_PLD_IO1
R681  Q_RES  33.2 1% EMPTY  pkg 0402LF  page 13 : 1 = SPI_BMC_IO2_R ; 2 = QSPI_2_PLD_IO2
R682  Q_RES  33.2 1% EMPTY  pkg 0402LF  page 13 : 1 = SPI_BMC_IO3_R ; 2 = QSPI_2_PLD_IO3
R683  Q_RES  4.7K 1% CHIP  pkg 0402LF  page 13 : 1 = P3V3_AUX ; 2 = PU_SPI1WP_N
R684  Q_RES  1K 1% EMPTY  pkg 0402LF  page 14 : 1 = BMC_EMMC_WP_N ; 2 = GND
R685  Q_RES  1K 1% EMPTY  pkg 0402LF  page 14 : 1 = BMC_EMMC_CD_N ; 2 = GND
R686  Q_RES  4.7K 1% EMPTY  pkg 0402LF  page 14 : 1 = P3V3_AUX ; 2 = BMC_EMMC_WP_N
R687  Q_RES  4.7K 1% EMPTY  pkg 0402LF  page 14 : 1 = P3V3_AUX ; 2 = BMC_EMMC_CD_N
R688  Q_RES  33.2 1% CHIP  pkg 0402LF  page 13 : 1 = RST_SGPIO_RESET_BMC_N ; 2 = RST_SGPIO_RESET_N
R689  Q_RES  33.2 1% EMPTY  pkg 0402LF  page 13 : 1 = IRQ_SGPIO_N ; 2 = IRQ_SGPIO_BMC_N
R690  Q_RES  33.2 1% CHIP  pkg 0402LF  page 35 : 1 = IRQ_SGPIO_R_N ; 2 = IRQ_SGPIO_N
R691  Q_RES  33.2 1% CHIP  pkg 0402LF  page 35 : 1 = RST_SGPIO_RESET_R_N ; 2 = RST_SGPIO_RESET_N
R692  Q_RES  2.2K 5% CHIP  pkg 0402LF  page 27 : 1 = P3V3_AUX ; 2 = SMB_BMC_MM15_SDA
R693  Q_RES  33.2 1% CHIP  pkg 0402LF  page 29 : 1 = DEBUG_PORT_PRSNT ; 2 = DEBUG_PORT_PRSNT_R
